# S9S_MB_2U (Grand Teton) — schematic netlist excerpt (pin names and nets, part order shuffled) for the footprints in the layout excerpt that follows; sources: Cadence DE-HDL packaged netlist, KiCad conversion of 03242023_DA0F0TMBIJ0_F0T_Motherboard_J_brd_V01_OCP.brd

PC2207  Q_CAP  1UF 25V 10% X6S  pkg C0402  page 192 : A = P12V_AUX ; B = GND
PR1769  Q_RES  3.3 1% CHIP  pkg 0402LF  page 268 : A = SW_PVCCIN_CPU0_BOOT3 ; B = SW_PVCCIN_CPU0_BOOT3_R

(kicad_pcb
	(version 20260206)
	(generator "pcbnew")
	(generator_version "10.0")
	(general
		(thickness 1.6)
		(legacy_teardrops no)
	)
	(paper "A4")
	(title_block
		(title "03242023_DA0F0TMBIJ0_F0T_Motherboard_J_brd_V01_OCP.brd")
		(comment 1 "Grand Teton / footprints 2732-2733 of 6105")
	)
	(layers
		(0 "F.Cu" signal "TOP")
		(4 "In1.Cu" signal "GND")
		(6 "In2.Cu" signal "IN1")
		(8 "In3.Cu" signal "GND1")
		(10 "In4.Cu" signal "IN2")
		(12 "In5.Cu" signal "GND2")
		(14 "In6.Cu" signal "IN3")
		(16 "In7.Cu" signal "GND3")
		(18 "In8.Cu" signal "VCC")
		(20 "In9.Cu" signal "VCC1")
		(22 "In10.Cu" signal "GND4")
		(24 "In11.Cu" signal "IN4")
		(26 "In12.Cu" signal "GND5")
		(28 "In13.Cu" signal "IN5")
		(30 "In14.Cu" signal "GND6")
		(32 "In15.Cu" signal "IN6")
		(34 "In16.Cu" signal "GND7")
		(2 "B.Cu" signal "BOTTOM")
		(9 "F.Adhes" user "F.Adhesive")
		(11 "B.Adhes" user "B.Adhesive")
		(13 "F.Paste" user "Package Geometry/Pastemask Top")
		(15 "B.Paste" user "Package Geometry/Pastemask Bottom")
		(5 "F.SilkS" user "Ref Des/Silkscreen Top")
		(7 "B.SilkS" user "Ref Des/Silkscreen Bottom")
		(1 "F.Mask" user "Board Geometry/Soldermask Top")
		(3 "B.Mask" user "Board Geometry/Soldermask Bottom")
		(17 "Dwgs.User" user "User.Drawings")
		(19 "Cmts.User" user "User.Comments")
		(21 "Eco1.User" user "User.Eco1")
		(23 "Eco2.User" user "User.Eco2")
		(25 "Edge.Cuts" user "Board Geometry/Outline")
		(27 "Margin" user)
		(31 "F.CrtYd" user "Package Geometry/Place Bound Top")
		(29 "B.CrtYd" user "Package Geometry/Place Bound Bottom")
		(35 "F.Fab" user "Ref Des/Assembly Top")
		(33 "B.Fab" user "Ref Des/Assembly Bottom")
	)
	(footprint ""
		(layer "F.Cu")
		(at 256.889504 -43.504612 180)
		(property "Reference" "PC2207"
			(at 0 0 180)
			(layer "F.SilkS")
			(hide yes)
			(effects
				(font
					(size 1.27 1.27)
				)
			)
		)
		(property "Value" ""
			(at 0 0 180)
			(layer "F.Fab")
			(effects
				(font
					(size 1.27 1.27)
				)
			)
		)
		(duplicate_pad_numbers_are_jumpers no)
		(fp_line
			(start 0.7874 0.4064)
			(end -0.7874 0.4064)
			(stroke
				(width 0.1524)
				(type default)
			)
			(layer "F.SilkS")
		)
		(fp_line
			(start 0.7874 -0.4064)
			(end 0.7874 0.4064)
			(stroke
				(width 0.1524)
				(type default)
			)
			(layer "F.SilkS")
		)
		(fp_line
			(start -0.7874 0.4064)
			(end -0.7874 -0.4064)
			(stroke
				(width 0.1524)
				(type default)
			)
			(layer "F.SilkS")
		)
		(fp_line
			(start -0.7874 -0.4064)
			(end 0.7874 -0.4064)
			(stroke
				(width 0.1524)
				(type default)
			)
			(layer "F.SilkS")
		)
		(fp_line
			(start 0.67945 0.3048)
			(end 0.120396 0.3048)
			(stroke
				(width 0.1)
				(type default)
			)
			(layer "F.Fab")
		)
		(fp_line
			(start 0.67945 -0.3048)
			(end 0.67945 0.3048)
			(stroke
				(width 0.1)
				(type default)
			)
			(layer "F.Fab")
		)
		(fp_line
			(start 0.12065 -0.2794)
			(end 0.12065 -0.3048)
			(stroke
				(width 0.1)
				(type default)
			)
			(layer "F.Fab")
		)
		(fp_line
			(start 0.12065 -0.3048)
			(end 0.67945 -0.3048)
			(stroke
				(width 0.1)
				(type default)
			)
			(layer "F.Fab")
		)
		(fp_line
			(start 0.120396 0.3048)
			(end 0.120396 0.2794)
			(stroke
				(width 0.1)
				(type default)
			)
			(layer "F.Fab")
		)
		(fp_line
			(start 0.120396 0.2794)
			(end -0.12065 0.2794)
			(stroke
				(width 0.1)
				(type default)
			)
			(layer "F.Fab")
		)
		(fp_line
			(start -0.12065 0.3048)
			(end -0.67945 0.3048)
			(stroke
				(width 0.1)
				(type default)
			)
			(layer "F.Fab")
		)
		(fp_line
			(start -0.12065 0.2794)
			(end -0.12065 0.3048)
			(stroke
				(width 0.1)
				(type default)
			)
			(layer "F.Fab")
		)
		(fp_line
			(start -0.12065 -0.2794)
			(end 0.12065 -0.2794)
			(stroke
				(width 0.1)
				(type default)
			)
			(layer "F.Fab")
		)
		(fp_line
			(start -0.12065 -0.305054)
			(end -0.12065 -0.2794)
			(stroke
				(width 0.1)
				(type default)
			)
			(layer "F.Fab")
		)
		(fp_line
			(start -0.67945 0.3048)
			(end -0.67945 -0.305054)
			(stroke
				(width 0.1)
				(type default)
			)
			(layer "F.Fab")
		)
		(fp_line
			(start -0.67945 -0.305054)
			(end -0.12065 -0.305054)
			(stroke
				(width 0.1)
				(type default)
			)
			(layer "F.Fab")
		)
		(pad "1" smd circle
			(at -0.40005 0 180)
			(size 0 0)
			(layers "F.Cu" "F.Mask" "F.Paste")
			(net "P12V_AUX")
		)
		(pad "2" smd circle
			(at 0.40005 0 180)
			(size 0 0)
			(layers "F.Cu" "F.Mask" "F.Paste")
			(net "GND")
		)
	)
	(footprint ""
		(layer "F.Cu")
		(at 361.953556 -338.180172 90)
		(property "Reference" "PR1769"
			(at 0 0 90)
			(layer "F.SilkS")
			(hide yes)
			(effects
				(font
					(size 1.27 1.27)
				)
			)
		)
		(property "Value" ""
			(at 0 0 90)
			(layer "F.Fab")
			(effects
				(font
					(size 1.27 1.27)
				)
			)
		)
		(duplicate_pad_numbers_are_jumpers no)
		(fp_line
			(start 0.7874 -0.4064)
			(end 0.7874 0.4064)
			(stroke
				(width 0.1524)
				(type default)
			)
			(layer "F.SilkS")
		)
		(fp_line
			(start -0.7874 -0.4064)
			(end 0.7874 -0.4064)
			(stroke
				(width 0.1524)
				(type default)
			)
			(layer "F.SilkS")
		)
		(fp_line
			(start 0.7874 0.4064)
			(end -0.7874 0.4064)
			(stroke
				(width 0.1524)
				(type default)
			)
			(layer "F.SilkS")
		)
		(fp_line
			(start -0.7874 0.4064)
			(end -0.7874 -0.4064)
			(stroke
				(width 0.1524)
				(type default)
			)
			(layer "F.SilkS")
		)
		(fp_line
			(start -0.12065 -0.305054)
			(end -0.12065 -0.2794)
			(stroke
				(width 0.1)
				(type default)
			)
			(layer "F.Fab")
		)
		(fp_line
			(start -0.67945 -0.305054)
			(end -0.12065 -0.305054)
			(stroke
				(width 0.1)
				(type default)
			)
			(layer "F.Fab")
		)
		(fp_line
			(start 0.67945 -0.3048)
			(end 0.67945 0.3048)
			(stroke
				(width 0.1)
				(type default)
			)
			(layer "F.Fab")
		)
		(fp_line
			(start 0.12065 -0.3048)
			(end 0.67945 -0.3048)
			(stroke
				(width 0.1)
				(type default)
			)
			(layer "F.Fab")
		)
		(fp_line
			(start 0.12065 -0.2794)
			(end 0.12065 -0.3048)
			(stroke
				(width 0.1)
				(type default)
			)
			(layer "F.Fab")
		)
		(fp_line
			(start -0.12065 -0.2794)
			(end 0.12065 -0.2794)
			(stroke
				(width 0.1)
				(type default)
			)
			(layer "F.Fab")
		)
		(fp_line
			(start 0.120396 0.2794)
			(end -0.12065 0.2794)
			(stroke
				(width 0.1)
				(type default)
			)
			(layer "F.Fab")
		)
		(fp_line
			(start -0.12065 0.2794)
			(end -0.12065 0.3048)
			(stroke
				(width 0.1)
				(type default)
			)
			(layer "F.Fab")
		)
		(fp_line
			(start 0.67945 0.3048)
			(end 0.120396 0.3048)
			(stroke
				(width 0.1)
				(type default)
			)
			(layer "F.Fab")
		)
		(fp_line
			(start 0.120396 0.3048)
			(end 0.120396 0.2794)
			(stroke
				(width 0.1)
				(type default)
			)
			(layer "F.Fab")
		)
		(fp_line
			(start -0.12065 0.3048)
			(end -0.67945 0.3048)
			(stroke
				(width 0.1)
				(type default)
			)
			(layer "F.Fab")
		)
		(fp_line
			(start -0.67945 0.3048)
			(end -0.67945 -0.305054)
			(stroke
				(width 0.1)
				(type default)
			)
			(layer "F.Fab")
		)
		(pad "1" smd circle
			(at -0.40005 0 90)
			(size 0 0)
			(layers "F.Cu" "F.Mask" "F.Paste")
			(net "SW_PVCCIN_CPU0_BOOT3")
		)
		(pad "2" smd circle
			(at 0.40005 0 90)
			(size 0 0)
			(layers "F.Cu" "F.Mask" "F.Paste")
			(net "SW_PVCCIN_CPU0_BOOT3_R")
		)
	)
)
